# BASEBOARD_FAB2 (Tioga Pass) — schematic netlist excerpt (pin names and nets, part order shuffled) for the footprints in the layout excerpt that follows; sources: Cadence DE-HDL packaged netlist, KiCad conversion of Wiwynn_Tioga_Pass_MB.brd

C1M15  CAP  0.22UF 16V 10% X7R  pkg 0402  page 106 : A = P3E_CPU0_PE3_OCP_TXN<11> ; B = P3E_OCP_CPU0_PE3_C_TXN<11>
R12W18  4D02R2F-GP  1%  pkg SMD-RG2  page 197 : \1\ = P12V_STBY ; \2\ = P12V_NVDIMM_KLM_D
R4W1  RES  4.75K 1% CHIP  pkg 0402  page 191 : A = P3V3_STBY ; B = PU_CPLD1_PT20D_PROGRAMN

(kicad_pcb
	(version 20260206)
	(generator "pcbnew")
	(generator_version "10.0")
	(general
		(thickness 1.6)
		(legacy_teardrops no)
	)
	(paper "A4")
	(title_block
		(title "Wiwynn_Tioga_Pass_MB.brd")
		(comment 1 "Tioga Pass / footprints 4718-4720 of 4770")
	)
	(layers
		(0 "F.Cu" signal "TOP")
		(4 "In1.Cu" signal "L2GND")
		(6 "In2.Cu" signal "L3")
		(8 "In3.Cu" signal "L4GND")
		(10 "In4.Cu" signal "L5")
		(12 "In5.Cu" signal "L6GND")
		(14 "In6.Cu" signal "L7VCC")
		(16 "In7.Cu" signal "L8VCC")
		(18 "In8.Cu" signal "L9GND")
		(20 "In9.Cu" signal "L10")
		(22 "In10.Cu" signal "L11GND")
		(24 "In11.Cu" signal "L12")
		(26 "In12.Cu" signal "L13GND")
		(2 "B.Cu" signal "BOTTOM")
		(9 "F.Adhes" user "F.Adhesive")
		(11 "B.Adhes" user "B.Adhesive")
		(13 "F.Paste" user "Package Geometry/Pastemask Top")
		(15 "B.Paste" user "Package Geometry/Pastemask Bottom")
		(5 "F.SilkS" user "Ref Des/Silkscreen Top")
		(7 "B.SilkS" user "Ref Des/Silkscreen Bottom")
		(1 "F.Mask" user "Board Geometry/Soldermask Top")
		(3 "B.Mask" user "Board Geometry/Soldermask Bottom")
		(17 "Dwgs.User" user "User.Drawings")
		(19 "Cmts.User" user "User.Comments")
		(21 "Eco1.User" user "User.Eco1")
		(23 "Eco2.User" user "User.Eco2")
		(25 "Edge.Cuts" user "Board Geometry/Outline")
		(27 "Margin" user)
		(31 "F.CrtYd" user "Package Geometry/Place Bound Top")
		(29 "B.CrtYd" user "Package Geometry/Place Bound Bottom")
		(35 "F.Fab" user "Ref Des/Assembly Top")
		(33 "B.Fab" user "Ref Des/Assembly Bottom")
	)
	(footprint ""
		(layer "B.Cu")
		(at 371.983 -65.6844 180)
		(property "Reference" "R4W1"
			(at 0.8382 -0.67818 180)
			(unlocked yes)
			(layer "B.SilkS")
			(effects
				(font
					(size 0.4064 0.254)
					(thickness 0.1524)
				)
				(justify left mirror)
			)
		)
		(property "Value" ""
			(at 0 0 0)
			(layer "B.Fab")
			(effects
				(font
					(size 1.27 1.27)
				)
				(justify mirror)
			)
		)
		(duplicate_pad_numbers_are_jumpers no)
		(fp_poly
			(pts
				(xy 0.2794 -0.1016) (xy -0.2794 -0.1016) (xy -0.2794 0.9906) (xy 0.2794 0.9906)
			)
			(stroke
				(width 0)
				(type default)
			)
			(fill no)
			(layer "B.CrtYd")
		)
		(fp_line
			(start 0.2794 0.9906)
			(end -0.2794 0.9906)
			(stroke
				(width 0.1)
				(type default)
			)
			(layer "B.Fab")
		)
		(fp_line
			(start 0.2794 -0.1016)
			(end 0.2794 0.9906)
			(stroke
				(width 0.1)
				(type default)
			)
			(layer "B.Fab")
		)
		(fp_line
			(start -0.2794 0.9906)
			(end -0.2794 -0.1016)
			(stroke
				(width 0.1)
				(type default)
			)
			(layer "B.Fab")
		)
		(fp_line
			(start -0.2794 -0.1016)
			(end 0.2794 -0.1016)
			(stroke
				(width 0.1)
				(type default)
			)
			(layer "B.Fab")
		)
		(pad "1" smd rect
			(at 0 0)
			(size 0.508 0.508)
			(layers "B.Cu" "B.Mask" "B.Paste")
			(net "P3V3_STBY")
		)
		(pad "2" smd rect
			(at 0 0.889)
			(size 0.508 0.508)
			(layers "B.Cu" "B.Mask" "B.Paste")
			(net "PU_CPLD1_PT20D_PROGRAMN")
		)
		(zone
			(layer "B.Cu")
			(hatch none 0.5)
			(connect_pads
				(clearance 0)
			)
			(min_thickness 0.25)
			(keepout
				(tracks not_allowed)
				(vias allowed)
				(pads allowed)
				(copperpour not_allowed)
				(footprints allowed)
			)
			(placement
				(enabled no)
				(sheetname "")
			)
			(fill
				(thermal_gap 0.5)
				(thermal_bridge_width 0.5)
				(island_removal_mode 0)
			)
			(polygon
				(pts
					(xy 371.729 -66.3194) (xy 372.237 -66.3194) (xy 372.237 -65.9384) (xy 371.729 -65.9384)
				)
			)
		)
		(zone
			(layer "B.Cu")
			(hatch none 0.5)
			(connect_pads
				(clearance 0)
			)
			(min_thickness 0.25)
			(keepout
				(tracks allowed)
				(vias not_allowed)
				(pads allowed)
				(copperpour not_allowed)
				(footprints allowed)
			)
			(placement
				(enabled no)
				(sheetname "")
			)
			(fill
				(thermal_gap 0.5)
				(thermal_bridge_width 0.5)
				(island_removal_mode 0)
			)
			(polygon
				(pts
					(xy 371.729 -65.9384) (xy 372.237 -65.9384) (xy 372.237 -66.3194) (xy 371.729 -66.3194)
				)
			)
		)
	)
	(footprint ""
		(layer "B.Cu")
		(at 11.6332 -128.8034 90)
		(property "Reference" "R12W18"
			(at 0 0 90)
			(layer "B.SilkS")
			(hide yes)
			(effects
				(font
					(size 1.27 1.27)
				)
				(justify mirror)
			)
		)
		(property "Value" "*"
			(at -0.064008 -4.108196 90)
			(unlocked yes)
			(layer "B.Fab")
			(hide yes)
			(effects
				(font
					(size 1.27 1.016)
					(thickness 0.1524)
				)
				(justify mirror)
			)
		)
		(property "Device Type" "4D02R2F-GP_SMD-RG2-4D02R2F-GP,A"
			(at -0.064008 -5.632196 90)
			(unlocked yes)
			(layer "B.Fab")
			(hide yes)
			(effects
				(font
					(size 1.27 1.016)
					(thickness 0.1524)
				)
				(justify mirror)
			)
		)
		(duplicate_pad_numbers_are_jumpers no)
		(fp_line
			(start 0.508 -0.9398)
			(end 0.508 0.9398)
			(stroke
				(width 0.1524)
				(type default)
			)
			(layer "B.SilkS")
		)
		(fp_line
			(start -0.508 -0.9398)
			(end 0.508 -0.9398)
			(stroke
				(width 0.1524)
				(type default)
			)
			(layer "B.SilkS")
		)
		(fp_rect
			(start 0.508 0.9398)
			(end -0.508 -0.9398)
			(stroke
				(width 0)
				(type default)
			)
			(fill no)
			(layer "B.CrtYd")
		)
		(fp_rect
			(start 0.508 0.9398)
			(end -0.508 -0.9398)
			(stroke
				(width 0)
				(type default)
			)
			(fill no)
			(layer "B.Fab")
		)
		(pad "1" smd custom
			(at 0 -0.4445 270)
			(size 0.1397 0.1397)
			(layers "B.Cu" "B.Mask" "B.Paste")
			(net "P12V_STBY")
			(options
				(clearance outline)
				(anchor circle)
			)
			(primitives
				(gr_poly
					(pts
						(arc
							(start -0.1778 0.2794)
							(mid -0.249642 0.249642)
							(end -0.2794 0.1778)
						)
						(arc
							(start -0.2794 -0.1778)
							(mid -0.249642 -0.249642)
							(end -0.1778 -0.2794)
						)
						(arc
							(start 0.1778 -0.2794)
							(mid 0.249642 -0.249642)
							(end 0.2794 -0.1778)
						)
						(arc
							(start 0.2794 0.1778)
							(mid 0.249642 0.249642)
							(end 0.1778 0.2794)
						)
					)
					(width 0)
					(fill yes)
				)
			)
		)
		(pad "2" smd custom
			(at 0 0.4445 270)
			(size 0.1397 0.1397)
			(layers "B.Cu" "B.Mask" "B.Paste")
			(net "P12V_NVDIMM_KLM_D")
			(options
				(clearance outline)
				(anchor circle)
			)
			(primitives
				(gr_poly
					(pts
						(arc
							(start -0.1778 0.2794)
							(mid -0.249642 0.249642)
							(end -0.2794 0.1778)
						)
						(arc
							(start -0.2794 -0.1778)
							(mid -0.249642 -0.249642)
							(end -0.1778 -0.2794)
						)
						(arc
							(start 0.1778 -0.2794)
							(mid 0.249642 -0.249642)
							(end 0.2794 -0.1778)
						)
						(arc
							(start 0.2794 0.1778)
							(mid 0.249642 0.249642)
							(end 0.1778 0.2794)
						)
					)
					(width 0)
					(fill yes)
				)
			)
		)
	)
	(footprint ""
		(layer "B.Cu")
		(at 452.501 -116.49202)
		(property "Reference" "C1M15"
			(at 0 0 0)
			(layer "B.SilkS")
			(hide yes)
			(effects
				(font
					(size 1.27 1.27)
				)
				(justify mirror)
			)
		)
		(property "Value" ""
			(at 0 0 0)
			(layer "B.Fab")
			(effects
				(font
					(size 1.27 1.27)
				)
				(justify mirror)
			)
		)
		(duplicate_pad_numbers_are_jumpers no)
		(fp_rect
			(start -0.3048 0.9906)
			(end 0.3048 -0.1016)
			(stroke
				(width 0)
				(type default)
			)
			(fill no)
			(layer "B.CrtYd")
		)
		(fp_line
			(start -0.3048 -0.1016)
			(end 0.3048 -0.1016)
			(stroke
				(width 0.1)
				(type default)
			)
			(layer "B.Fab")
		)
		(fp_line
			(start -0.3048 0.9906)
			(end -0.3048 -0.1016)
			(stroke
				(width 0.1)
				(type default)
			)
			(layer "B.Fab")
		)
		(fp_line
			(start 0.3048 -0.1016)
			(end 0.3048 0.9906)
			(stroke
				(width 0.1)
				(type default)
			)
			(layer "B.Fab")
		)
		(fp_line
			(start 0.3048 0.9906)
			(end -0.3048 0.9906)
			(stroke
				(width 0.1)
				(type default)
			)
			(layer "B.Fab")
		)
		(pad "1" smd rect
			(at 0 0 180)
			(size 0.508 0.508)
			(layers "B.Cu" "B.Mask" "B.Paste")
			(net "P3E_CPU0_PE3_OCP_TXN<11>")
		)
		(pad "2" smd rect
			(at 0 0.889 180)
			(size 0.508 0.508)
			(layers "B.Cu" "B.Mask" "B.Paste")
			(net "P3E_OCP_CPU0_PE3_C_TXN<11>")
		)
		(zone
			(layer "B.Cu")
			(hatch none 0.5)
			(connect_pads
				(clearance 0)
			)
			(min_thickness 0.25)
			(keepout
				(tracks allowed)
				(vias not_allowed)
				(pads allowed)
				(copperpour not_allowed)
				(footprints allowed)
			)
			(placement
				(enabled no)
				(sheetname "")
			)
			(fill
				(thermal_gap 0.5)
				(thermal_bridge_width 0.5)
				(island_removal_mode 0)
			)
			(polygon
				(pts
					(xy 452.247 -115.85702) (xy 452.755 -115.85702) (xy 452.755 -116.23802) (xy 452.247 -116.23802)
				)
			)
		)
		(zone
			(layer "B.Cu")
			(hatch none 0.5)
			(connect_pads
				(clearance 0)
			)
			(min_thickness 0.25)
			(keepout
				(tracks not_allowed)
				(vias allowed)
				(pads allowed)
				(copperpour not_allowed)
				(footprints allowed)
			)
			(placement
				(enabled no)
				(sheetname "")
			)
			(fill
				(thermal_gap 0.5)
				(thermal_bridge_width 0.5)
				(island_removal_mode 0)
			)
			(polygon
				(pts
					(xy 452.247 -115.85702) (xy 452.755 -115.85702) (xy 452.755 -116.23802) (xy 452.247 -116.23802)
				)
			)
		)
	)
)
